# T6G (Grand Teton) — schematic netlist excerpt (pin names and nets, part order shuffled) for the footprints in the layout excerpt that follows; sources: Cadence DE-HDL packaged netlist, KiCad conversion of 04192023_DAF0TMB3IC0_F0TG_MB_C_brd_V02_OCP.brd

R1114  Q_RES  4.7K 5% EMPTY  pkg 0201LF  page 309 : A = P1V8_CPU0_RT_1D ; B = TEST0_RT_CPU0_P3
PC573_5  Q_CAP  22UF 16V 20% X6S  pkg C0805  page 196 : A = SW_P12V_AUX_PVDDCR_CPU0_P0_FLT ; B = GND
C302  Q_CAP  10PF 50V 5% EMPTY  pkg 0402  page 193 : A = SVID_PVDDCR_CPU0_P0_SVC_R ; B = GND
C337  Q_CAP  1UF 4V 20% X6S  pkg 0201  page 334 : A = P0V9_CPU1_RT1_2A ; B = GND

(kicad_pcb
	(version 20260206)
	(generator "pcbnew")
	(generator_version "10.0")
	(general
		(thickness 1.6)
		(legacy_teardrops no)
	)
	(paper "A4")
	(title_block
		(title "04192023_DAF0TMB3IC0_F0TG_MB_C_brd_V02_OCP.brd")
		(comment 1 "Grand Teton / footprints 7778-7781 of 8354")
	)
	(layers
		(0 "F.Cu" signal "TOP")
		(4 "In1.Cu" signal "GND")
		(6 "In2.Cu" signal "IN1")
		(8 "In3.Cu" signal "GND1")
		(10 "In4.Cu" signal "IN2")
		(12 "In5.Cu" signal "GND2")
		(14 "In6.Cu" signal "IN3")
		(16 "In7.Cu" signal "GND3")
		(18 "In8.Cu" signal "VCC")
		(20 "In9.Cu" signal "VCC1")
		(22 "In10.Cu" signal "GND4")
		(24 "In11.Cu" signal "IN4")
		(26 "In12.Cu" signal "GND5")
		(28 "In13.Cu" signal "IN5")
		(30 "In14.Cu" signal "GND6")
		(32 "In15.Cu" signal "IN6")
		(34 "In16.Cu" signal "GND7")
		(2 "B.Cu" signal "BOTTOM")
		(9 "F.Adhes" user "F.Adhesive")
		(11 "B.Adhes" user "B.Adhesive")
		(13 "F.Paste" user "Package Geometry/Pastemask Top")
		(15 "B.Paste" user "Package Geometry/Pastemask Bottom")
		(5 "F.SilkS" user "Ref Des/Silkscreen Top")
		(7 "B.SilkS" user "Ref Des/Silkscreen Bottom")
		(1 "F.Mask" user "Board Geometry/Soldermask Top")
		(3 "B.Mask" user "Board Geometry/Soldermask Bottom")
		(17 "Dwgs.User" user "User.Drawings")
		(19 "Cmts.User" user "User.Comments")
		(21 "Eco1.User" user "User.Eco1")
		(23 "Eco2.User" user "User.Eco2")
		(25 "Edge.Cuts" user "Board Geometry/Outline")
		(27 "Margin" user)
		(31 "F.CrtYd" user "Package Geometry/Place Bound Top")
		(29 "B.CrtYd" user "Package Geometry/Place Bound Bottom")
		(35 "F.Fab" user "Ref Des/Assembly Top")
		(33 "B.Fab" user "Ref Des/Assembly Bottom")
	)
	(footprint ""
		(layer "B.Cu")
		(at 370.905278 -145.536158)
		(property "Reference" "C302"
			(at 0 0 0)
			(layer "B.SilkS")
			(hide yes)
			(effects
				(font
					(size 1.27 1.27)
				)
				(justify mirror)
			)
		)
		(property "Value" ""
			(at 0 0 0)
			(layer "B.Fab")
			(effects
				(font
					(size 1.27 1.27)
				)
				(justify mirror)
			)
		)
		(duplicate_pad_numbers_are_jumpers no)
		(fp_line
			(start -0.7874 -0.4064)
			(end -0.7874 0.4064)
			(stroke
				(width 0.1524)
				(type default)
			)
			(layer "B.SilkS")
		)
		(fp_line
			(start -0.7874 0.4064)
			(end 0.7874 0.4064)
			(stroke
				(width 0.1524)
				(type default)
			)
			(layer "B.SilkS")
		)
		(fp_line
			(start 0.7874 -0.4064)
			(end -0.7874 -0.4064)
			(stroke
				(width 0.1524)
				(type default)
			)
			(layer "B.SilkS")
		)
		(fp_line
			(start 0.7874 0.4064)
			(end 0.7874 -0.4064)
			(stroke
				(width 0.1524)
				(type default)
			)
			(layer "B.SilkS")
		)
		(fp_line
			(start -0.67945 -0.3048)
			(end -0.67945 0.3048)
			(stroke
				(width 0.1)
				(type default)
			)
			(layer "B.Fab")
		)
		(fp_line
			(start -0.67945 0.3048)
			(end -0.120396 0.3048)
			(stroke
				(width 0.1)
				(type default)
			)
			(layer "B.Fab")
		)
		(fp_line
			(start -0.12065 -0.3048)
			(end -0.67945 -0.3048)
			(stroke
				(width 0.1)
				(type default)
			)
			(layer "B.Fab")
		)
		(fp_line
			(start -0.12065 -0.2794)
			(end -0.12065 -0.3048)
			(stroke
				(width 0.1)
				(type default)
			)
			(layer "B.Fab")
		)
		(fp_line
			(start -0.120396 0.2794)
			(end 0.12065 0.2794)
			(stroke
				(width 0.1)
				(type default)
			)
			(layer "B.Fab")
		)
		(fp_line
			(start -0.120396 0.3048)
			(end -0.120396 0.2794)
			(stroke
				(width 0.1)
				(type default)
			)
			(layer "B.Fab")
		)
		(fp_line
			(start 0.12065 -0.305054)
			(end 0.12065 -0.2794)
			(stroke
				(width 0.1)
				(type default)
			)
			(layer "B.Fab")
		)
		(fp_line
			(start 0.12065 -0.2794)
			(end -0.12065 -0.2794)
			(stroke
				(width 0.1)
				(type default)
			)
			(layer "B.Fab")
		)
		(fp_line
			(start 0.12065 0.2794)
			(end 0.12065 0.3048)
			(stroke
				(width 0.1)
				(type default)
			)
			(layer "B.Fab")
		)
		(fp_line
			(start 0.12065 0.3048)
			(end 0.67945 0.3048)
			(stroke
				(width 0.1)
				(type default)
			)
			(layer "B.Fab")
		)
		(fp_line
			(start 0.67945 -0.305054)
			(end 0.12065 -0.305054)
			(stroke
				(width 0.1)
				(type default)
			)
			(layer "B.Fab")
		)
		(fp_line
			(start 0.67945 0.3048)
			(end 0.67945 -0.305054)
			(stroke
				(width 0.1)
				(type default)
			)
			(layer "B.Fab")
		)
		(pad "1" smd circle
			(at 0.40005 0 180)
			(size 0 0)
			(layers "B.Cu" "B.Mask" "B.Paste")
			(net "SVID_PVDDCR_CPU0_P0_SVC_R")
		)
		(pad "2" smd circle
			(at -0.40005 0 180)
			(size 0 0)
			(layers "B.Cu" "B.Mask" "B.Paste")
			(net "GND")
		)
	)
	(footprint ""
		(layer "B.Cu")
		(at 82.306414 -386.766562 90)
		(property "Reference" "C337"
			(at 0 0 90)
			(layer "B.SilkS")
			(hide yes)
			(effects
				(font
					(size 1.27 1.27)
				)
				(justify mirror)
			)
		)
		(property "Value" ""
			(at 0 0 90)
			(layer "B.Fab")
			(effects
				(font
					(size 1.27 1.27)
				)
				(justify mirror)
			)
		)
		(duplicate_pad_numbers_are_jumpers no)
		(fp_line
			(start 0.299974 -0.150114)
			(end -0.299974 -0.150114)
			(stroke
				(width 0.1)
				(type default)
			)
			(layer "B.Fab")
		)
		(fp_line
			(start -0.299974 -0.150114)
			(end -0.299974 0.150114)
			(stroke
				(width 0.1)
				(type default)
			)
			(layer "B.Fab")
		)
		(fp_line
			(start 0.299974 0.150114)
			(end 0.299974 -0.150114)
			(stroke
				(width 0.1)
				(type default)
			)
			(layer "B.Fab")
		)
		(fp_line
			(start -0.299974 0.150114)
			(end 0.299974 0.150114)
			(stroke
				(width 0.1)
				(type default)
			)
			(layer "B.Fab")
		)
		(pad "1" smd rect
			(at 0.2667 0 270)
			(size 0.3048 0.381)
			(layers "B.Cu" "B.Mask" "B.Paste")
			(net "P0V9_CPU1_RT1_2A")
		)
		(pad "2" smd rect
			(at -0.2667 0 270)
			(size 0.3048 0.381)
			(layers "B.Cu" "B.Mask" "B.Paste")
			(net "GND")
		)
	)
	(footprint ""
		(layer "B.Cu")
		(at 365.09579 -393.96416 180)
		(property "Reference" "R1114"
			(at 0 0 0)
			(layer "B.SilkS")
			(hide yes)
			(effects
				(font
					(size 1.27 1.27)
				)
				(justify mirror)
			)
		)
		(property "Value" ""
			(at 0 0 0)
			(layer "B.Fab")
			(effects
				(font
					(size 1.27 1.27)
				)
				(justify mirror)
			)
		)
		(duplicate_pad_numbers_are_jumpers no)
		(fp_line
			(start 0.32512 0.175006)
			(end 0.32512 -0.175006)
			(stroke
				(width 0.1)
				(type default)
			)
			(layer "B.Fab")
		)
		(fp_line
			(start 0.32512 -0.175006)
			(end -0.32512 -0.175006)
			(stroke
				(width 0.1)
				(type default)
			)
			(layer "B.Fab")
		)
		(fp_line
			(start -0.32512 0.175006)
			(end 0.32512 0.175006)
			(stroke
				(width 0.1)
				(type default)
			)
			(layer "B.Fab")
		)
		(fp_line
			(start -0.32512 -0.175006)
			(end -0.32512 0.175006)
			(stroke
				(width 0.1)
				(type default)
			)
			(layer "B.Fab")
		)
		(pad "1" smd rect
			(at 0.2667 0)
			(size 0.3048 0.381)
			(layers "B.Cu" "B.Mask" "B.Paste")
			(net "P1V8_CPU0_RT_1D")
		)
		(pad "2" smd rect
			(at -0.2667 0 180)
			(size 0.3048 0.381)
			(layers "B.Cu" "B.Mask" "B.Paste")
			(net "TEST0_RT_CPU0_P3")
		)
	)
	(footprint ""
		(layer "B.Cu")
		(at 355.006656 -169.619676 -90)
		(property "Reference" "PC573_5"
			(at 0 0 90)
			(layer "B.SilkS")
			(hide yes)
			(effects
				(font
					(size 1.27 1.27)
				)
				(justify mirror)
			)
		)
		(property "Value" ""
			(at 0 0 90)
			(layer "B.Fab")
			(effects
				(font
					(size 1.27 1.27)
				)
				(justify mirror)
			)
		)
		(duplicate_pad_numbers_are_jumpers no)
		(fp_line
			(start -1.524 0.762)
			(end 1.524 0.762)
			(stroke
				(width 0.1524)
				(type default)
			)
			(layer "B.SilkS")
		)
		(fp_line
			(start 1.524 0.762)
			(end 1.524 -0.762)
			(stroke
				(width 0.1524)
				(type default)
			)
			(layer "B.SilkS")
		)
		(fp_line
			(start -1.524 -0.762)
			(end -1.524 0.762)
			(stroke
				(width 0.1524)
				(type default)
			)
			(layer "B.SilkS")
		)
		(fp_line
			(start 1.524 -0.762)
			(end -1.524 -0.762)
			(stroke
				(width 0.1524)
				(type default)
			)
			(layer "B.SilkS")
		)
		(fp_line
			(start -1.1049 0.724916)
			(end -1.1049 -0.724916)
			(stroke
				(width 0.1)
				(type default)
			)
			(layer "B.Fab")
		)
		(fp_line
			(start 1.1049 0.724916)
			(end -1.1049 0.724916)
			(stroke
				(width 0.1)
				(type default)
			)
			(layer "B.Fab")
		)
		(fp_line
			(start -1.1049 -0.724916)
			(end 1.1049 -0.724916)
			(stroke
				(width 0.1)
				(type default)
			)
			(layer "B.Fab")
		)
		(fp_line
			(start 1.1049 -0.724916)
			(end 1.1049 0.724916)
			(stroke
				(width 0.1)
				(type default)
			)
			(layer "B.Fab")
		)
		(pad "1" smd rect
			(at 0.889 0 270)
			(size 1.016 1.27)
			(layers "B.Cu" "B.Mask" "B.Paste")
			(net "SW_P12V_AUX_PVDDCR_CPU0_P0_FLT")
		)
		(pad "2" smd rect
			(at -0.889 0 270)
			(size 1.016 1.27)
			(layers "B.Cu" "B.Mask" "B.Paste")
			(net "GND")
		)
	)
)
